(kicad_pcb
	(version 20241229)
	(generator "pcbnew")
	(generator_version "9.0")
	(general
		(thickness 1.61)
		(legacy_teardrops no)
	)
	(paper "A3")
	(title_block
		(title "SO-DIMM DDR5 Tester")
		(date "2025-11-26")
		(rev "1.3.0")
		(comment 9 "footprint 59 of 627 (U4), pads 650-676 of 676")
	)
	(layers
		(0 "F.Cu" signal)
		(4 "In1.Cu" power)
		(6 "In2.Cu" mixed)
		(8 "In3.Cu" power)
		(10 "In4.Cu" mixed)
		(12 "In5.Cu" power)
		(14 "In6.Cu" mixed)
		(16 "In7.Cu" power)
		(18 "In8.Cu" power)
		(20 "In9.Cu" mixed)
		(22 "In10.Cu" power)
		(2 "B.Cu" signal)
		(9 "F.Adhes" user "F.Adhesive")
		(11 "B.Adhes" user "B.Adhesive")
		(13 "F.Paste" user)
		(15 "B.Paste" user)
		(5 "F.SilkS" user "F.Silkscreen")
		(7 "B.SilkS" user "B.Silkscreen")
		(1 "F.Mask" user)
		(3 "B.Mask" user)
		(17 "Dwgs.User" user "User.Drawings")
		(19 "Cmts.User" user "User.Comments")
		(21 "Eco1.User" user "User.Eco1")
		(23 "Eco2.User" user "User.Eco2")
		(25 "Edge.Cuts" user)
		(27 "Margin" user)
		(31 "F.CrtYd" user "F.Courtyard")
		(29 "B.CrtYd" user "B.Courtyard")
		(35 "F.Fab" user)
		(33 "B.Fab" user)
	)
	(footprint "antmicro-footprints:BGA-676_27x27mm_Layout26x26_P1x1mm_FFG676"
		(layer "F.Cu")
		(at 138.875501 174.801 180)
		(descr "FPGA XC7K160TFBG676")
		(tags "FPGA XC7K160TFBG676")
		(property "Reference" "U4"
			(at -12.224499 14.051 180)
			(layer "F.SilkS")
			(effects
				(font
					(size 0.7 0.7)
					(thickness 0.15)
				)
				(justify left bottom)
			)
		)
		(property "Value" "XC7K160T-FFG676"
			(at 0 15.5 180)
			(layer "F.Fab")
			(effects
				(font
					(size 0.7 0.7)
					(thickness 0.15)
				)
				(justify left bottom)
			)
		)
		(property "Datasheet" "https://docs.xilinx.com/v/u/en-US/ds180_7Series_Overview"
			(at 0 0 180)
			(layer "F.Fab")
			(hide yes)
			(effects
				(font
					(size 1.27 1.27)
					(thickness 0.15)
				)
			)
		)
		(property "Author" "Antmicro"
			(at 277.751002 349.602 0)
			(layer "F.Fab")
			(hide yes)
			(effects
				(font
					(size 1 1)
					(thickness 0.15)
				)
			)
		)
		(property "License" "Apache-2.0"
			(at 277.751002 349.602 0)
			(layer "F.Fab")
			(hide yes)
			(effects
				(font
					(size 1 1)
					(thickness 0.15)
				)
			)
		)
		(property "MPN" "XC7K160T-FFG676"
			(at 277.751002 349.602 0)
			(layer "F.Fab")
			(hide yes)
			(effects
				(font
					(size 1 1)
					(thickness 0.15)
				)
			)
		)
		(property "Manufacturer" "AMD-Xilinx"
			(at 277.751002 349.602 0)
			(layer "F.Fab")
			(hide yes)
			(effects
				(font
					(size 1 1)
					(thickness 0.15)
				)
			)
		)
		(sheetname "/FPGA Config/")
		(sheetfile "fpga-config.kicad_sch")
		(attr smd)
		(pad "W26" smd circle
			(at 12.499 5.499 180)
			(size 0.5 0.5)
			(layers "F.Cu" "F.Mask" "F.Paste")
			(net 673 "/Ethernet/ETH.RXD0")
			(pinfunction "IO_L5N_T0_12")
			(pintype "bidirectional")
			(die_length 15.45)
		)
		(pad "Y1" smd circle
			(at -12.5 6.499 180)
			(size 0.5 0.5)
			(layers "F.Cu" "F.Mask" "F.Paste")
			(net 264 "/DDR5 SODIMM/B.~{DM2}")
			(pinfunction "IO_L10N_T1_34")
			(pintype "bidirectional")
			(die_length 20.111)
		)
		(pad "Y2" smd circle
			(at -11.5 6.499 180)
			(size 0.5 0.5)
			(layers "F.Cu" "F.Mask" "F.Paste")
			(net 269 "/DDR5 SODIMM/B.DQ21")
			(pinfunction "IO_L7N_T1_34")
			(pintype "bidirectional")
			(die_length 18.743)
		)
		(pad "Y3" smd circle
			(at -10.5 6.499 180)
			(size 0.5 0.5)
			(layers "F.Cu" "F.Mask" "F.Paste")
			(net 261 "/DDR5 SODIMM/B.DQ18")
			(pinfunction "IO_L7P_T1_34")
			(pintype "bidirectional")
			(die_length 18.285)
		)
		(pad "Y4" smd circle
			(at -9.5 6.499 180)
			(size 0.5 0.5)
			(layers "F.Cu" "F.Mask" "F.Paste")
			(net 206 "+1V1")
			(pinfunction "VCCO_34")
			(pintype "passive")
		)
		(pad "Y5" smd circle
			(at -8.5 6.499 180)
			(size 0.5 0.5)
			(layers "F.Cu" "F.Mask" "F.Paste")
			(net 238 "/DDR5 SODIMM/B.DQ10")
			(pinfunction "IO_L17N_T2_34")
			(pintype "bidirectional")
			(die_length 15.693)
		)
		(pad "Y6" smd circle
			(at -7.5 6.499 180)
			(size 0.5 0.5)
			(layers "F.Cu" "F.Mask" "F.Paste")
			(net 233 "/DDR5 SODIMM/B.DQ9")
			(pinfunction "IO_L17P_T2_34")
			(pintype "bidirectional")
			(die_length 17.912)
		)
		(pad "Y7" smd circle
			(at -6.5 6.499 180)
			(size 0.5 0.5)
			(layers "F.Cu" "F.Mask" "F.Paste")
			(net 181 "/DDR5 SODIMM/B.CA1")
			(pinfunction "IO_L4N_T0_33")
			(pintype "bidirectional")
			(die_length 13.835)
		)
		(pad "Y8" smd circle
			(at -5.5 6.499 180)
			(size 0.5 0.5)
			(layers "F.Cu" "F.Mask" "F.Paste")
			(net 180 "/DDR5 SODIMM/B.~{CS0}")
			(pinfunction "IO_L4P_T0_33")
			(pintype "bidirectional")
			(die_length 13.201)
		)
		(pad "Y9" smd circle
			(at -4.5 6.499 180)
			(size 0.5 0.5)
			(layers "F.Cu" "F.Mask" "F.Paste")
			(net 1 "GND")
			(pinfunction "GND")
			(pintype "passive")
		)
		(pad "Y10" smd circle
			(at -3.5 6.499 180)
			(size 0.5 0.5)
			(layers "F.Cu" "F.Mask" "F.Paste")
			(net 177 "/DDR5 SODIMM/B.CA4")
			(pinfunction "IO_L5N_T0_33")
			(pintype "bidirectional")
			(die_length 14.206)
		)
		(pad "Y11" smd circle
			(at -2.5 6.499 180)
			(size 0.5 0.5)
			(layers "F.Cu" "F.Mask" "F.Paste")
			(net 176 "/DDR5 SODIMM/B.CA5")
			(pinfunction "IO_L5P_T0_33")
			(pintype "bidirectional")
			(die_length 15.036)
		)
		(pad "Y12" smd circle
			(at -1.5 6.499 180)
			(size 0.5 0.5)
			(layers "F.Cu" "F.Mask" "F.Paste")
			(net 168 "/DDR5 SODIMM/B.CA9")
			(pinfunction "IO_L18N_T2_33")
			(pintype "bidirectional")
			(die_length 14.615)
		)
		(pad "Y13" smd circle
			(at -0.5 6.499 180)
			(size 0.5 0.5)
			(layers "F.Cu" "F.Mask" "F.Paste")
			(net 169 "/DDR5 SODIMM/B.CA8")
			(pinfunction "IO_L18P_T2_33")
			(pintype "bidirectional")
			(die_length 15.191)
		)
		(pad "Y14" smd circle
			(at 0.499 6.499 180)
			(size 0.5 0.5)
			(layers "F.Cu" "F.Mask" "F.Paste")
			(net 206 "+1V1")
			(pinfunction "VCCO_32")
			(pintype "passive")
		)
		(pad "Y15" smd circle
			(at 1.499 6.499 180)
			(size 0.5 0.5)
			(layers "F.Cu" "F.Mask" "F.Paste")
			(net 96 "/DDR5 SODIMM/A.DQS2_P")
			(pinfunction "IO_L9P_T1_DQS_32")
			(pintype "bidirectional")
			(die_length 13.423)
		)
		(pad "Y16" smd circle
			(at 2.499 6.499 180)
			(size 0.5 0.5)
			(layers "F.Cu" "F.Mask" "F.Paste")
			(net 95 "/DDR5 SODIMM/A.DQS2_N")
			(pinfunction "IO_L9N_T1_DQS_32")
			(pintype "bidirectional")
			(die_length 13.009)
		)
		(pad "Y17" smd circle
			(at 3.499 6.499 180)
			(size 0.5 0.5)
			(layers "F.Cu" "F.Mask" "F.Paste")
			(net 72 "/DDR5 SODIMM/A.DQ6")
			(pinfunction "IO_L19P_T3_32")
			(pintype "bidirectional")
			(die_length 15.853)
		)
		(pad "Y18" smd circle
			(at 4.499 6.499 180)
			(size 0.5 0.5)
			(layers "F.Cu" "F.Mask" "F.Paste")
			(net 10 "/FPGA banks HP/VREF")
			(pinfunction "IO_L19N_T3_VREF_32")
			(pintype "bidirectional")
			(die_length 15)
		)
		(pad "Y19" smd circle
			(at 5.499 6.499 180)
			(size 0.5 0.5)
			(layers "F.Cu" "F.Mask" "F.Paste")
			(net 1 "GND")
			(pinfunction "GND")
			(pintype "passive")
		)
		(pad "Y20" smd circle
			(at 6.499 6.499 180)
			(size 0.5 0.5)
			(layers "F.Cu" "F.Mask" "F.Paste")
			(net 734 "/Ethernet/ETH.~{INT}")
			(pinfunction "IO_25_12")
			(pintype "bidirectional")
			(die_length 8.585)
		)
		(pad "Y21" smd circle
			(at 7.499 6.499 180)
			(size 0.5 0.5)
			(layers "F.Cu" "F.Mask" "F.Paste")
			(net 735 "/Ethernet/ETH.TXD3")
			(pinfunction "IO_L15N_T2_DQS_12")
			(pintype "bidirectional")
			(die_length 9.864)
		)
		(pad "Y22" smd circle
			(at 8.499 6.499 180)
			(size 0.5 0.5)
			(layers "F.Cu" "F.Mask" "F.Paste")
			(net 736 "/Ethernet/ETH.TXD2")
			(pinfunction "IO_L13P_T2_MRCC_12")
			(pintype "bidirectional")
			(die_length 11.571)
		)
		(pad "Y23" smd circle
			(at 9.499 6.499 180)
			(size 0.5 0.5)
			(layers "F.Cu" "F.Mask" "F.Paste")
			(net 678 "/Ethernet/ETH.RXC")
			(pinfunction "IO_L12P_T1_MRCC_12")
			(pintype "bidirectional")
			(die_length 12.692)
		)
		(pad "Y24" smd circle
			(at 10.499 6.499 180)
			(size 0.5 0.5)
			(layers "F.Cu" "F.Mask" "F.Paste")
			(net 200 "+3V3")
			(pinfunction "VCCO_12")
			(pintype "passive")
		)
		(pad "Y25" smd circle
			(at 11.499 6.499 180)
			(size 0.5 0.5)
			(layers "F.Cu" "F.Mask" "F.Paste")
			(net 677 "/Ethernet/ETH.RX_CTL")
			(pinfunction "IO_L10P_T1_12")
			(pintype "bidirectional")
			(die_length 14.135)
		)
		(pad "Y26" smd circle
			(at 12.499 6.499 180)
			(size 0.5 0.5)
			(layers "F.Cu" "F.Mask" "F.Paste")
			(net 737 "/Ethernet/ETH.TXD1")
			(pinfunction "IO_L10N_T1_12")
			(pintype "bidirectional")
			(die_length 15.98)
		)
	)
)
